(kicad_pcb
	(version 20260206)
	(generator "pcbnew")
	(generator_version "10.0")
	(general
		(thickness 1.6)
		(legacy_teardrops no)
	)
	(paper "A4")
	(title_block
		(title "Bryce Canyon_R.DPB_16317-1_OCP.brd")
		(comment 1 "Bryce Canyon / footprints 1269-1271 of 2099")
	)
	(layers
		(0 "F.Cu" signal "TOP")
		(4 "In1.Cu" signal "L2GND")
		(6 "In2.Cu" signal "L3")
		(8 "In3.Cu" signal "L4VCC")
		(10 "In4.Cu" signal "L5VCC")
		(12 "In5.Cu" signal "L6")
		(14 "In6.Cu" signal "L7GND")
		(2 "B.Cu" signal "BOTTOM")
		(9 "F.Adhes" user "F.Adhesive")
		(11 "B.Adhes" user "B.Adhesive")
		(13 "F.Paste" user "Package Geometry/Pastemask Top")
		(15 "B.Paste" user "Package Geometry/Pastemask Bottom")
		(5 "F.SilkS" user "Ref Des/Silkscreen Top")
		(7 "B.SilkS" user "Ref Des/Silkscreen Bottom")
		(1 "F.Mask" user "Board Geometry/Soldermask Top")
		(3 "B.Mask" user "Board Geometry/Soldermask Bottom")
		(17 "Dwgs.User" user "User.Drawings")
		(19 "Cmts.User" user "User.Comments")
		(21 "Eco1.User" user "User.Eco1")
		(23 "Eco2.User" user "User.Eco2")
		(25 "Edge.Cuts" user "Board Geometry/Outline")
		(27 "Margin" user)
		(31 "F.CrtYd" user "Package Geometry/Place Bound Top")
		(29 "B.CrtYd" user "Package Geometry/Place Bound Bottom")
		(35 "F.Fab" user "Ref Des/Assembly Top")
		(33 "B.Fab" user "Ref Des/Assembly Bottom")
	)
	(footprint ""
		(layer "F.Cu")
		(at 393.674854 -178.799998)
		(property "Reference" ""
			(at 0 0 0)
			(layer "F.SilkS")
			(hide yes)
			(effects
				(font
					(size 1.27 1.27)
				)
			)
		)
		(property "Value" "*"
			(at -8.398764 -8.057642 0)
			(unlocked yes)
			(layer "F.Fab")
			(hide yes)
			(effects
				(font
					(size 1.016 1.016)
					(thickness 0.1524)
				)
			)
		)
		(duplicate_pad_numbers_are_jumpers no)
		(fp_poly
			(pts
				(arc
					(start 7.3152 0)
					(mid 0 7.3152)
					(end -7.3152 0)
				)
				(arc
					(start -7.3152 -5.9944)
					(mid 0 -13.3096)
					(end 7.3152 -5.9944)
				)
			)
			(stroke
				(width 0)
				(type default)
			)
			(fill no)
			(layer "B.CrtYd")
		)
		(fp_poly
			(pts
				(arc
					(start 7.3152 0)
					(mid 0 7.3152)
					(end -7.3152 0)
				)
				(arc
					(start -7.3152 -5.9944)
					(mid 0 -13.3096)
					(end 7.3152 -5.9944)
				)
			)
			(stroke
				(width 0)
				(type default)
			)
			(fill no)
			(layer "F.CrtYd")
		)
		(fp_poly
			(pts
				(arc
					(start 7.3152 0)
					(mid 0 7.3152)
					(end -7.3152 0)
				)
				(arc
					(start -7.3152 -5.9944)
					(mid 0 -13.3096)
					(end 7.3152 -5.9944)
				)
			)
			(stroke
				(width 0)
				(type default)
			)
			(fill no)
			(layer "B.Fab")
		)
		(fp_poly
			(pts
				(arc
					(start 7.3152 0)
					(mid 0 7.3152)
					(end -7.3152 0)
				)
				(arc
					(start -7.3152 -5.9944)
					(mid 0 -13.3096)
					(end 7.3152 -5.9944)
				)
			)
			(stroke
				(width 0)
				(type default)
			)
			(fill no)
			(layer "F.Fab")
		)
		(pad "1" thru_hole oval
			(at 0 0)
			(size 14.0208 20.0152)
			(drill 0.0254
				(offset 0 -2.9972)
			)
			(layers "*.Cu" "*.Mask")
			(remove_unused_layers no)
			(net "Net_43")
			(clearance -1.002284)
			(thermal_gap 0.1524)
			(padstack
				(mode front_inner_back)
				(layer "Inner"
					(shape custom)
					(size 2.928012 2.928012)
					(options
						(anchor circle)
					)
					(primitives
						(gr_poly
							(pts
								(arc
									(start 4.571746 -2.084324)
									(mid 0.000333 7.430372)
									(end -4.571492 -2.084324)
								)
								(arc
									(start -4.571492 -2.084324)
									(mid -3.570296 -3.611977)
									(end -2.875026 -5.30098)
								)
								(arc
									(start -2.875026 -5.30098)
									(mid 0.000217 -7.43089)
									(end 2.87528 -5.30098)
								)
								(arc
									(start 2.87528 -5.30098)
									(mid 3.570511 -3.611956)
									(end 4.571746 -2.084324)
								)
							)
							(width 0)
							(fill yes)
						)
					)
					(clearance 0.1524)
				)
				(layer "B.Cu"
					(shape oval)
					(size 14.0208 20.0152)
					(offset 0 -2.9972)
					(clearance -1.002284)
				)
			)
		)
		(zone
			(layers "F.Cu" "B.Cu" "In1.Cu" "In2.Cu" "In3.Cu" "In4.Cu" "In5.Cu" "In6.Cu")
			(hatch none 0.5)
			(connect_pads
				(clearance 0)
			)
			(min_thickness 0.25)
			(keepout
				(tracks not_allowed)
				(vias allowed)
				(pads allowed)
				(copperpour not_allowed)
				(footprints allowed)
			)
			(placement
				(enabled no)
				(sheetname "")
			)
			(fill
				(thermal_gap 0.5)
				(thermal_bridge_width 0.5)
				(island_removal_mode 0)
			)
			(polygon
				(pts
					(arc
						(start 386.664454 -184.794398)
						(mid 393.674854 -191.804798)
						(end 400.685254 -184.794398)
					)
					(arc
						(start 400.685254 -178.799998)
						(mid 393.674854 -171.789598)
						(end 386.664454 -178.799998)
					)
				)
			)
		)
	)
	(footprint ""
		(layer "F.Cu")
		(at 416.284664 -245.219474 -90)
		(property "Reference" "C145"
			(at 0 0 270)
			(layer "F.SilkS")
			(hide yes)
			(effects
				(font
					(size 1.27 1.27)
				)
			)
		)
		(property "Value" "SCD01U16V1KX-GP"
			(at -2.8321 -1.7399 270)
			(unlocked yes)
			(layer "F.Fab")
			(hide yes)
			(effects
				(font
					(size 1.016 1.016)
					(thickness 0.1524)
				)
			)
		)
		(property "Device Type" "C0201H13"
			(at -2.8321 -3.2639 270)
			(unlocked yes)
			(layer "F.Fab")
			(hide yes)
			(effects
				(font
					(size 1.016 1.016)
					(thickness 0.1524)
				)
			)
		)
		(duplicate_pad_numbers_are_jumpers no)
		(fp_rect
			(start -0.2794 0.6477)
			(end 0.2794 -0.6477)
			(stroke
				(width 0)
				(type default)
			)
			(fill no)
			(layer "F.CrtYd")
		)
		(fp_rect
			(start -0.2794 0.6477)
			(end 0.2794 -0.6477)
			(stroke
				(width 0)
				(type default)
			)
			(fill no)
			(layer "F.Fab")
		)
		(pad "1" smd custom
			(at 0 -0.2794 270)
			(size 0.0762 0.0762)
			(layers "F.Cu" "F.Mask" "F.Paste")
			(net "SAS_HDD_RX_N9")
			(options
				(clearance outline)
				(anchor circle)
			)
			(primitives
				(gr_poly
					(pts
						(arc
							(start 0.1524 -0.127)
							(mid 0.137521 -0.162921)
							(end 0.1016 -0.1778)
						)
						(arc
							(start -0.1016 -0.1778)
							(mid -0.137521 -0.162921)
							(end -0.1524 -0.127)
						)
						(arc
							(start -0.1524 0.127)
							(mid -0.137521 0.162921)
							(end -0.1016 0.1778)
						)
						(arc
							(start 0.1016 0.1778)
							(mid 0.137521 0.162921)
							(end 0.1524 0.127)
						)
					)
					(width 0)
					(fill yes)
				)
			)
		)
		(pad "2" smd custom
			(at 0 0.2794 270)
			(size 0.0762 0.0762)
			(layers "F.Cu" "F.Mask" "F.Paste")
			(net "PHY_SCC_B_TO_DRV_B_9_DN")
			(options
				(clearance outline)
				(anchor circle)
			)
			(primitives
				(gr_poly
					(pts
						(arc
							(start 0.1524 -0.127)
							(mid 0.137521 -0.162921)
							(end 0.1016 -0.1778)
						)
						(arc
							(start -0.1016 -0.1778)
							(mid -0.137521 -0.162921)
							(end -0.1524 -0.127)
						)
						(arc
							(start -0.1524 0.127)
							(mid -0.137521 0.162921)
							(end -0.1016 0.1778)
						)
						(arc
							(start 0.1016 0.1778)
							(mid 0.137521 0.162921)
							(end 0.1524 0.127)
						)
					)
					(width 0)
					(fill yes)
				)
			)
		)
	)
	(footprint ""
		(layer "F.Cu")
		(at 328.643996 -367.157 -90)
		(property "Reference" "D42"
			(at 0 0 270)
			(layer "F.SilkS")
			(hide yes)
			(effects
				(font
					(size 1.27 1.27)
				)
			)
		)
		(property "Value" "BAS16H-GP"
			(at 0 -5.5372 270)
			(unlocked yes)
			(layer "F.Fab")
			(hide yes)
			(effects
				(font
					(size 1.016 1.016)
					(thickness 0.1524)
				)
			)
		)
		(property "Device Type" "SOD123AKH48"
			(at 0 -7.0612 270)
			(unlocked yes)
			(layer "F.Fab")
			(hide yes)
			(effects
				(font
					(size 1.016 1.016)
					(thickness 0.1524)
				)
			)
		)
		(duplicate_pad_numbers_are_jumpers no)
		(fp_line
			(start 0.889 2.921)
			(end -0.889 2.921)
			(stroke
				(width 0.508)
				(type default)
			)
			(layer "F.SilkS")
		)
		(fp_line
			(start -1.016 2.667)
			(end 1.016 2.667)
			(stroke
				(width 0.1524)
				(type default)
			)
			(layer "F.SilkS")
		)
		(fp_line
			(start 1.016 2.667)
			(end 1.016 -2.667)
			(stroke
				(width 0.1524)
				(type default)
			)
			(layer "F.SilkS")
		)
		(fp_line
			(start -1.016 -2.667)
			(end -1.016 2.667)
			(stroke
				(width 0.1524)
				(type default)
			)
			(layer "F.SilkS")
		)
		(fp_line
			(start 1.016 -2.667)
			(end -1.016 -2.667)
			(stroke
				(width 0.1524)
				(type default)
			)
			(layer "F.SilkS")
		)
		(fp_rect
			(start -1.143 3.175)
			(end 1.143 -2.794)
			(stroke
				(width 0)
				(type default)
			)
			(fill no)
			(layer "F.CrtYd")
		)
		(fp_poly
			(pts
				(xy -1.143 -2.794) (xy 1.143 -2.794) (xy 1.143 3.175) (xy -1.143 3.175)
			)
			(stroke
				(width 0)
				(type default)
			)
			(fill no)
			(layer "F.Fab")
		)
		(pad "A" smd rect
			(at 0 -1.6891 270)
			(size 0.889 1.397)
			(layers "F.Cu" "F.Mask" "F.Paste")
			(net "FAN_2_TACH1")
		)
		(pad "K" smd rect
			(at 0 1.6891 270)
			(size 0.889 1.397)
			(layers "F.Cu" "F.Mask" "F.Paste")
			(net "P12V_IN")
		)
	)
)
